# T6G (Grand Teton) — schematic netlist excerpt (pin names and nets, part order shuffled) for the footprints in the layout excerpt that follows; sources: Cadence DE-HDL packaged netlist, KiCad conversion of 04192023_DAF0TMB3IC0_F0TG_MB_C_brd_V02_OCP.brd

R6274  Q_RES  0 5% CHIP  pkg 0402LF  page 179 : A = USB_HUB2_TI_VDD33_MRP_PROG_FUNC7 ; B = P3V3_AUX_CPU0_USB2_AVDD33
C961  Q_CAP_DIFFBUS  DIFF BUS_0.22UF 6.3V 20% X6S  pkg C0201  page 63 : \1\ = P5E_CPU0_P1_TX_C_DP<2> ; \2\ = P5E_CPU0_P1_TX_DP<2>
PC2168  Q_CAP  39PF 50V 5% NPO  pkg 0402  page 141 : A = P3V3_OCP_MODE_2 ; B = GND

(kicad_pcb
	(version 20260206)
	(generator "pcbnew")
	(generator_version "10.0")
	(general
		(thickness 1.6)
		(legacy_teardrops no)
	)
	(paper "A4")
	(title_block
		(title "04192023_DAF0TMB3IC0_F0TG_MB_C_brd_V02_OCP.brd")
		(comment 1 "Grand Teton / footprints 3052-3054 of 8354")
	)
	(layers
		(0 "F.Cu" signal "TOP")
		(4 "In1.Cu" signal "GND")
		(6 "In2.Cu" signal "IN1")
		(8 "In3.Cu" signal "GND1")
		(10 "In4.Cu" signal "IN2")
		(12 "In5.Cu" signal "GND2")
		(14 "In6.Cu" signal "IN3")
		(16 "In7.Cu" signal "GND3")
		(18 "In8.Cu" signal "VCC")
		(20 "In9.Cu" signal "VCC1")
		(22 "In10.Cu" signal "GND4")
		(24 "In11.Cu" signal "IN4")
		(26 "In12.Cu" signal "GND5")
		(28 "In13.Cu" signal "IN5")
		(30 "In14.Cu" signal "GND6")
		(32 "In15.Cu" signal "IN6")
		(34 "In16.Cu" signal "GND7")
		(2 "B.Cu" signal "BOTTOM")
		(9 "F.Adhes" user "F.Adhesive")
		(11 "B.Adhes" user "B.Adhesive")
		(13 "F.Paste" user "Package Geometry/Pastemask Top")
		(15 "B.Paste" user "Package Geometry/Pastemask Bottom")
		(5 "F.SilkS" user "Ref Des/Silkscreen Top")
		(7 "B.SilkS" user "Ref Des/Silkscreen Bottom")
		(1 "F.Mask" user "Board Geometry/Soldermask Top")
		(3 "B.Mask" user "Board Geometry/Soldermask Bottom")
		(17 "Dwgs.User" user "User.Drawings")
		(19 "Cmts.User" user "User.Comments")
		(21 "Eco1.User" user "User.Eco1")
		(23 "Eco2.User" user "User.Eco2")
		(25 "Edge.Cuts" user "Board Geometry/Outline")
		(27 "Margin" user)
		(31 "F.CrtYd" user "Package Geometry/Place Bound Top")
		(29 "B.CrtYd" user "Package Geometry/Place Bound Bottom")
		(35 "F.Fab" user "Ref Des/Assembly Top")
		(33 "B.Fab" user "Ref Des/Assembly Bottom")
	)
	(footprint ""
		(layer "F.Cu")
		(at 120.68175 -23.005796)
		(property "Reference" "R6274"
			(at 0 0 0)
			(layer "F.SilkS")
			(hide yes)
			(effects
				(font
					(size 1.27 1.27)
				)
			)
		)
		(property "Value" ""
			(at 0 0 0)
			(layer "F.Fab")
			(effects
				(font
					(size 1.27 1.27)
				)
			)
		)
		(duplicate_pad_numbers_are_jumpers no)
		(fp_line
			(start -0.7874 -0.4064)
			(end 0.7874 -0.4064)
			(stroke
				(width 0.1524)
				(type default)
			)
			(layer "F.SilkS")
		)
		(fp_line
			(start -0.7874 0.4064)
			(end -0.7874 -0.4064)
			(stroke
				(width 0.1524)
				(type default)
			)
			(layer "F.SilkS")
		)
		(fp_line
			(start 0.7874 -0.4064)
			(end 0.7874 0.4064)
			(stroke
				(width 0.1524)
				(type default)
			)
			(layer "F.SilkS")
		)
		(fp_line
			(start 0.7874 0.4064)
			(end -0.7874 0.4064)
			(stroke
				(width 0.1524)
				(type default)
			)
			(layer "F.SilkS")
		)
		(fp_line
			(start -0.67945 -0.305054)
			(end -0.12065 -0.305054)
			(stroke
				(width 0.1)
				(type default)
			)
			(layer "F.Fab")
		)
		(fp_line
			(start -0.67945 0.3048)
			(end -0.67945 -0.305054)
			(stroke
				(width 0.1)
				(type default)
			)
			(layer "F.Fab")
		)
		(fp_line
			(start -0.12065 -0.305054)
			(end -0.12065 -0.2794)
			(stroke
				(width 0.1)
				(type default)
			)
			(layer "F.Fab")
		)
		(fp_line
			(start -0.12065 -0.2794)
			(end 0.12065 -0.2794)
			(stroke
				(width 0.1)
				(type default)
			)
			(layer "F.Fab")
		)
		(fp_line
			(start -0.12065 0.2794)
			(end -0.12065 0.3048)
			(stroke
				(width 0.1)
				(type default)
			)
			(layer "F.Fab")
		)
		(fp_line
			(start -0.12065 0.3048)
			(end -0.67945 0.3048)
			(stroke
				(width 0.1)
				(type default)
			)
			(layer "F.Fab")
		)
		(fp_line
			(start 0.120396 0.2794)
			(end -0.12065 0.2794)
			(stroke
				(width 0.1)
				(type default)
			)
			(layer "F.Fab")
		)
		(fp_line
			(start 0.120396 0.3048)
			(end 0.120396 0.2794)
			(stroke
				(width 0.1)
				(type default)
			)
			(layer "F.Fab")
		)
		(fp_line
			(start 0.12065 -0.3048)
			(end 0.67945 -0.3048)
			(stroke
				(width 0.1)
				(type default)
			)
			(layer "F.Fab")
		)
		(fp_line
			(start 0.12065 -0.2794)
			(end 0.12065 -0.3048)
			(stroke
				(width 0.1)
				(type default)
			)
			(layer "F.Fab")
		)
		(fp_line
			(start 0.67945 -0.3048)
			(end 0.67945 0.3048)
			(stroke
				(width 0.1)
				(type default)
			)
			(layer "F.Fab")
		)
		(fp_line
			(start 0.67945 0.3048)
			(end 0.120396 0.3048)
			(stroke
				(width 0.1)
				(type default)
			)
			(layer "F.Fab")
		)
		(pad "1" smd circle
			(at -0.40005 0)
			(size 0 0)
			(layers "F.Cu" "F.Mask" "F.Paste")
			(net "USB_HUB2_TI_VDD33_MRP_PROG_FUNC7")
		)
		(pad "2" smd circle
			(at 0.40005 0)
			(size 0 0)
			(layers "F.Cu" "F.Mask" "F.Paste")
			(net "P3V3_AUX_CPU0_USB2_AVDD33")
		)
	)
	(footprint ""
		(layer "F.Cu")
		(at 331.517244 -381.41783 -90)
		(property "Reference" "C961"
			(at 0 0 270)
			(layer "F.SilkS")
			(hide yes)
			(effects
				(font
					(size 1.27 1.27)
				)
			)
		)
		(property "Value" ""
			(at 0 0 270)
			(layer "F.Fab")
			(effects
				(font
					(size 1.27 1.27)
				)
			)
		)
		(duplicate_pad_numbers_are_jumpers no)
		(fp_line
			(start -0.299974 0.150114)
			(end -0.299974 -0.150114)
			(stroke
				(width 0.1)
				(type default)
			)
			(layer "F.Fab")
		)
		(fp_line
			(start 0.299974 0.150114)
			(end -0.299974 0.150114)
			(stroke
				(width 0.1)
				(type default)
			)
			(layer "F.Fab")
		)
		(fp_line
			(start -0.299974 -0.150114)
			(end 0.299974 -0.150114)
			(stroke
				(width 0.1)
				(type default)
			)
			(layer "F.Fab")
		)
		(fp_line
			(start 0.299974 -0.150114)
			(end 0.299974 0.150114)
			(stroke
				(width 0.1)
				(type default)
			)
			(layer "F.Fab")
		)
		(pad "1" smd rect
			(at -0.2667 0 270)
			(size 0.3048 0.381)
			(layers "F.Cu" "F.Mask" "F.Paste")
			(net "P5E_CPU0_P1_TX_C_DP<2>")
		)
		(pad "2" smd rect
			(at 0.2667 0 270)
			(size 0.3048 0.381)
			(layers "F.Cu" "F.Mask" "F.Paste")
			(net "P5E_CPU0_P1_TX_DP<2>")
		)
	)
	(footprint ""
		(layer "F.Cu")
		(at 89.567512 -72.46366 90)
		(property "Reference" "PC2168"
			(at 0 0 90)
			(layer "F.SilkS")
			(hide yes)
			(effects
				(font
					(size 1.27 1.27)
				)
			)
		)
		(property "Value" ""
			(at 0 0 90)
			(layer "F.Fab")
			(effects
				(font
					(size 1.27 1.27)
				)
			)
		)
		(duplicate_pad_numbers_are_jumpers no)
		(fp_line
			(start 0.7874 -0.4064)
			(end 0.7874 0.4064)
			(stroke
				(width 0.1524)
				(type default)
			)
			(layer "F.SilkS")
		)
		(fp_line
			(start -0.7874 -0.4064)
			(end 0.7874 -0.4064)
			(stroke
				(width 0.1524)
				(type default)
			)
			(layer "F.SilkS")
		)
		(fp_line
			(start 0.7874 0.4064)
			(end -0.7874 0.4064)
			(stroke
				(width 0.1524)
				(type default)
			)
			(layer "F.SilkS")
		)
		(fp_line
			(start -0.7874 0.4064)
			(end -0.7874 -0.4064)
			(stroke
				(width 0.1524)
				(type default)
			)
			(layer "F.SilkS")
		)
		(fp_line
			(start -0.12065 -0.305054)
			(end -0.12065 -0.2794)
			(stroke
				(width 0.1)
				(type default)
			)
			(layer "F.Fab")
		)
		(fp_line
			(start -0.67945 -0.305054)
			(end -0.12065 -0.305054)
			(stroke
				(width 0.1)
				(type default)
			)
			(layer "F.Fab")
		)
		(fp_line
			(start 0.67945 -0.3048)
			(end 0.67945 0.3048)
			(stroke
				(width 0.1)
				(type default)
			)
			(layer "F.Fab")
		)
		(fp_line
			(start 0.12065 -0.3048)
			(end 0.67945 -0.3048)
			(stroke
				(width 0.1)
				(type default)
			)
			(layer "F.Fab")
		)
		(fp_line
			(start 0.12065 -0.2794)
			(end 0.12065 -0.3048)
			(stroke
				(width 0.1)
				(type default)
			)
			(layer "F.Fab")
		)
		(fp_line
			(start -0.12065 -0.2794)
			(end 0.12065 -0.2794)
			(stroke
				(width 0.1)
				(type default)
			)
			(layer "F.Fab")
		)
		(fp_line
			(start 0.120396 0.2794)
			(end -0.12065 0.2794)
			(stroke
				(width 0.1)
				(type default)
			)
			(layer "F.Fab")
		)
		(fp_line
			(start -0.12065 0.2794)
			(end -0.12065 0.3048)
			(stroke
				(width 0.1)
				(type default)
			)
			(layer "F.Fab")
		)
		(fp_line
			(start 0.67945 0.3048)
			(end 0.120396 0.3048)
			(stroke
				(width 0.1)
				(type default)
			)
			(layer "F.Fab")
		)
		(fp_line
			(start 0.120396 0.3048)
			(end 0.120396 0.2794)
			(stroke
				(width 0.1)
				(type default)
			)
			(layer "F.Fab")
		)
		(fp_line
			(start -0.12065 0.3048)
			(end -0.67945 0.3048)
			(stroke
				(width 0.1)
				(type default)
			)
			(layer "F.Fab")
		)
		(fp_line
			(start -0.67945 0.3048)
			(end -0.67945 -0.305054)
			(stroke
				(width 0.1)
				(type default)
			)
			(layer "F.Fab")
		)
		(pad "1" smd circle
			(at -0.40005 0 90)
			(size 0 0)
			(layers "F.Cu" "F.Mask" "F.Paste")
			(net "P3V3_OCP_MODE_2")
		)
		(pad "2" smd circle
			(at 0.40005 0 90)
			(size 0 0)
			(layers "F.Cu" "F.Mask" "F.Paste")
			(net "GND")
		)
	)
)
